(kicad_pcb
	(version 20260206)
	(generator "pcbnew")
	(generator_version "10.0")
	(general
		(thickness 1.6)
		(legacy_teardrops no)
	)
	(paper "A4")
	(title_block
		(title "12092022_DA0F0TYB4D0_F0T_Panel_BD_Front_D_brd_v02_OCP.brd")
		(comment 1 "Grand Teton / footprints 38-43 of 128")
	)
	(layers
		(0 "F.Cu" signal "TOP")
		(4 "In1.Cu" signal "GND")
		(6 "In2.Cu" signal "GND1")
		(2 "B.Cu" signal "BOTTOM")
		(9 "F.Adhes" user "F.Adhesive")
		(11 "B.Adhes" user "B.Adhesive")
		(13 "F.Paste" user "Package Geometry/Pastemask Top")
		(15 "B.Paste" user "Package Geometry/Pastemask Bottom")
		(5 "F.SilkS" user "Ref Des/Silkscreen Top")
		(7 "B.SilkS" user "Ref Des/Silkscreen Bottom")
		(1 "F.Mask" user "Board Geometry/Soldermask Top")
		(3 "B.Mask" user "Board Geometry/Soldermask Bottom")
		(17 "Dwgs.User" user "User.Drawings")
		(19 "Cmts.User" user "User.Comments")
		(21 "Eco1.User" user "User.Eco1")
		(23 "Eco2.User" user "User.Eco2")
		(25 "Edge.Cuts" user "Board Geometry/Outline")
		(27 "Margin" user)
		(31 "F.CrtYd" user "Package Geometry/Place Bound Top")
		(29 "B.CrtYd" user "Package Geometry/Place Bound Bottom")
		(35 "F.Fab" user "Ref Des/Assembly Top")
		(33 "B.Fab" user "Ref Des/Assembly Bottom")
	)
	(footprint ""
		(layer "F.Cu")
		(at 31.18485 -23.797768 -90)
		(property "Reference" "R51"
			(at 0.937768 1.05918 90)
			(unlocked yes)
			(layer "F.SilkS")
			(effects
				(font
					(size 0.7874 0.5842)
					(thickness 0.1524)
				)
				(justify left)
			)
		)
		(property "Value" ""
			(at 0 0 270)
			(layer "F.Fab")
			(effects
				(font
					(size 1.27 1.27)
				)
			)
		)
		(duplicate_pad_numbers_are_jumpers no)
		(fp_line
			(start -0.7874 0.4064)
			(end -0.7874 -0.4064)
			(stroke
				(width 0.1524)
				(type default)
			)
			(layer "F.SilkS")
		)
		(fp_line
			(start 0.7874 0.4064)
			(end -0.7874 0.4064)
			(stroke
				(width 0.1524)
				(type default)
			)
			(layer "F.SilkS")
		)
		(fp_line
			(start -0.7874 -0.4064)
			(end 0.7874 -0.4064)
			(stroke
				(width 0.1524)
				(type default)
			)
			(layer "F.SilkS")
		)
		(fp_line
			(start 0.7874 -0.4064)
			(end 0.7874 0.4064)
			(stroke
				(width 0.1524)
				(type default)
			)
			(layer "F.SilkS")
		)
		(fp_line
			(start -0.67945 0.3048)
			(end -0.67945 -0.305054)
			(stroke
				(width 0.1)
				(type default)
			)
			(layer "F.Fab")
		)
		(fp_line
			(start -0.12065 0.3048)
			(end -0.67945 0.3048)
			(stroke
				(width 0.1)
				(type default)
			)
			(layer "F.Fab")
		)
		(fp_line
			(start 0.120396 0.3048)
			(end 0.120396 0.2794)
			(stroke
				(width 0.1)
				(type default)
			)
			(layer "F.Fab")
		)
		(fp_line
			(start 0.67945 0.3048)
			(end 0.120396 0.3048)
			(stroke
				(width 0.1)
				(type default)
			)
			(layer "F.Fab")
		)
		(fp_line
			(start -0.12065 0.2794)
			(end -0.12065 0.3048)
			(stroke
				(width 0.1)
				(type default)
			)
			(layer "F.Fab")
		)
		(fp_line
			(start 0.120396 0.2794)
			(end -0.12065 0.2794)
			(stroke
				(width 0.1)
				(type default)
			)
			(layer "F.Fab")
		)
		(fp_line
			(start -0.12065 -0.2794)
			(end 0.12065 -0.2794)
			(stroke
				(width 0.1)
				(type default)
			)
			(layer "F.Fab")
		)
		(fp_line
			(start 0.12065 -0.2794)
			(end 0.12065 -0.3048)
			(stroke
				(width 0.1)
				(type default)
			)
			(layer "F.Fab")
		)
		(fp_line
			(start 0.12065 -0.3048)
			(end 0.67945 -0.3048)
			(stroke
				(width 0.1)
				(type default)
			)
			(layer "F.Fab")
		)
		(fp_line
			(start 0.67945 -0.3048)
			(end 0.67945 0.3048)
			(stroke
				(width 0.1)
				(type default)
			)
			(layer "F.Fab")
		)
		(fp_line
			(start -0.67945 -0.305054)
			(end -0.12065 -0.305054)
			(stroke
				(width 0.1)
				(type default)
			)
			(layer "F.Fab")
		)
		(fp_line
			(start -0.12065 -0.305054)
			(end -0.12065 -0.2794)
			(stroke
				(width 0.1)
				(type default)
			)
			(layer "F.Fab")
		)
		(pad "1" smd rect
			(at -0.40005 0 90)
			(size 0.4572 0.508)
			(layers "F.Cu" "F.Mask" "F.Paste")
			(net "USB2_DN")
		)
		(pad "2" smd rect
			(at 0.40005 0 90)
			(size 0.4572 0.508)
			(layers "F.Cu" "F.Mask" "F.Paste")
			(net "USB2_DEBUG_DN")
		)
	)
	(footprint ""
		(layer "F.Cu")
		(at 5.969 -58.293 180)
		(property "Reference" "R28"
			(at 2.794 -0.40767 0)
			(unlocked yes)
			(layer "F.SilkS")
			(effects
				(font
					(size 0.7874 0.5842)
					(thickness 0.1524)
				)
			)
		)
		(property "Value" ""
			(at 0 0 180)
			(layer "F.Fab")
			(effects
				(font
					(size 1.27 1.27)
				)
			)
		)
		(duplicate_pad_numbers_are_jumpers no)
		(fp_line
			(start 0.7874 0.4064)
			(end -0.7874 0.4064)
			(stroke
				(width 0.1524)
				(type default)
			)
			(layer "F.SilkS")
		)
		(fp_line
			(start 0.7874 -0.4064)
			(end 0.7874 0.4064)
			(stroke
				(width 0.1524)
				(type default)
			)
			(layer "F.SilkS")
		)
		(fp_line
			(start -0.7874 0.4064)
			(end -0.7874 -0.4064)
			(stroke
				(width 0.1524)
				(type default)
			)
			(layer "F.SilkS")
		)
		(fp_line
			(start -0.7874 -0.4064)
			(end 0.7874 -0.4064)
			(stroke
				(width 0.1524)
				(type default)
			)
			(layer "F.SilkS")
		)
		(fp_line
			(start 0.67945 0.3048)
			(end 0.120396 0.3048)
			(stroke
				(width 0.1)
				(type default)
			)
			(layer "F.Fab")
		)
		(fp_line
			(start 0.67945 -0.3048)
			(end 0.67945 0.3048)
			(stroke
				(width 0.1)
				(type default)
			)
			(layer "F.Fab")
		)
		(fp_line
			(start 0.12065 -0.2794)
			(end 0.12065 -0.3048)
			(stroke
				(width 0.1)
				(type default)
			)
			(layer "F.Fab")
		)
		(fp_line
			(start 0.12065 -0.3048)
			(end 0.67945 -0.3048)
			(stroke
				(width 0.1)
				(type default)
			)
			(layer "F.Fab")
		)
		(fp_line
			(start 0.120396 0.3048)
			(end 0.120396 0.2794)
			(stroke
				(width 0.1)
				(type default)
			)
			(layer "F.Fab")
		)
		(fp_line
			(start 0.120396 0.2794)
			(end -0.12065 0.2794)
			(stroke
				(width 0.1)
				(type default)
			)
			(layer "F.Fab")
		)
		(fp_line
			(start -0.12065 0.3048)
			(end -0.67945 0.3048)
			(stroke
				(width 0.1)
				(type default)
			)
			(layer "F.Fab")
		)
		(fp_line
			(start -0.12065 0.2794)
			(end -0.12065 0.3048)
			(stroke
				(width 0.1)
				(type default)
			)
			(layer "F.Fab")
		)
		(fp_line
			(start -0.12065 -0.2794)
			(end 0.12065 -0.2794)
			(stroke
				(width 0.1)
				(type default)
			)
			(layer "F.Fab")
		)
		(fp_line
			(start -0.12065 -0.305054)
			(end -0.12065 -0.2794)
			(stroke
				(width 0.1)
				(type default)
			)
			(layer "F.Fab")
		)
		(fp_line
			(start -0.67945 0.3048)
			(end -0.67945 -0.305054)
			(stroke
				(width 0.1)
				(type default)
			)
			(layer "F.Fab")
		)
		(fp_line
			(start -0.67945 -0.305054)
			(end -0.12065 -0.305054)
			(stroke
				(width 0.1)
				(type default)
			)
			(layer "F.Fab")
		)
		(pad "1" smd circle
			(at -0.40005 0 180)
			(size 0 0)
			(layers "F.Cu" "F.Mask" "F.Paste")
			(net "REV_ID<2>")
		)
		(pad "2" smd circle
			(at 0.40005 0 180)
			(size 0 0)
			(layers "F.Cu" "F.Mask" "F.Paste")
			(net "GND")
		)
	)
	(footprint ""
		(layer "F.Cu")
		(at 33.887664 -3.610864)
		(property "Reference" "U6"
			(at -4.931664 1.732534 0)
			(unlocked yes)
			(layer "F.SilkS")
			(effects
				(font
					(size 0.7874 0.5842)
					(thickness 0.1524)
				)
				(justify left)
			)
		)
		(property "Value" ""
			(at 0 0 0)
			(layer "F.Fab")
			(effects
				(font
					(size 1.27 1.27)
				)
			)
		)
		(duplicate_pad_numbers_are_jumpers no)
		(fp_line
			(start -3.447796 -2.500122)
			(end -3.447796 2.500122)
			(stroke
				(width 0.1524)
				(type default)
			)
			(layer "F.SilkS")
		)
		(fp_line
			(start -3.447796 2.500122)
			(end 3.447796 2.500122)
			(stroke
				(width 0.1524)
				(type default)
			)
			(layer "F.SilkS")
		)
		(fp_line
			(start -1.484122 -2.500122)
			(end -3.447796 -2.500122)
			(stroke
				(width 0.1524)
				(type default)
			)
			(layer "F.SilkS")
		)
		(fp_line
			(start 0 -1.016)
			(end -1.484122 -2.500122)
			(stroke
				(width 0.1524)
				(type default)
			)
			(layer "F.SilkS")
		)
		(fp_line
			(start 1.484122 -2.500122)
			(end 0 -1.016)
			(stroke
				(width 0.1524)
				(type default)
			)
			(layer "F.SilkS")
		)
		(fp_line
			(start 3.447796 -2.500122)
			(end 1.484122 -2.500122)
			(stroke
				(width 0.1524)
				(type default)
			)
			(layer "F.SilkS")
		)
		(fp_line
			(start 3.447796 2.500122)
			(end 3.447796 -2.500122)
			(stroke
				(width 0.1524)
				(type default)
			)
			(layer "F.SilkS")
		)
		(fp_poly
			(pts
				(xy -4.5974 -2.413) (xy -4.5974 -1.397) (xy -3.5814 -1.905)
			)
			(stroke
				(width 0)
				(type default)
			)
			(fill yes)
			(layer "F.SilkS")
		)
		(fp_line
			(start -1.999996 -2.500122)
			(end -1.999996 2.500122)
			(stroke
				(width 0.1)
				(type default)
			)
			(layer "F.Fab")
		)
		(fp_line
			(start -1.999996 2.500122)
			(end 1.999996 2.500122)
			(stroke
				(width 0.1)
				(type default)
			)
			(layer "F.Fab")
		)
		(fp_line
			(start 1.999996 -2.500122)
			(end -1.999996 -2.500122)
			(stroke
				(width 0.1)
				(type default)
			)
			(layer "F.Fab")
		)
		(fp_line
			(start 1.999996 2.500122)
			(end 1.999996 -2.500122)
			(stroke
				(width 0.1)
				(type default)
			)
			(layer "F.Fab")
		)
		(fp_poly
			(pts
				(xy -4.5974 -2.413) (xy -4.5974 -1.397) (xy -3.5814 -1.905)
			)
			(stroke
				(width 0)
				(type default)
			)
			(fill yes)
			(layer "F.Fab")
		)
		(pad "1" smd rect
			(at -2.649982 -1.905 270)
			(size 0.6096 1.3208)
			(layers "F.Cu" "F.Mask" "F.Paste")
			(net "SMB_TMP75_SDA")
		)
		(pad "2" smd rect
			(at -2.649982 -0.635 270)
			(size 0.6096 1.3208)
			(layers "F.Cu" "F.Mask" "F.Paste")
			(net "SMB_TMP75_SCL")
		)
		(pad "3" smd rect
			(at -2.649982 0.635 270)
			(size 0.6096 1.3208)
			(layers "F.Cu" "F.Mask" "F.Paste")
			(net "THERMAL_OS")
		)
		(pad "4" smd rect
			(at -2.649982 1.905 270)
			(size 0.6096 1.3208)
			(layers "F.Cu" "F.Mask" "F.Paste")
			(net "GND")
		)
		(pad "5" smd rect
			(at 2.649982 1.905 270)
			(size 0.6096 1.3208)
			(layers "F.Cu" "F.Mask" "F.Paste")
			(net "THERMAL_ADDR_A2")
		)
		(pad "6" smd rect
			(at 2.649982 0.635 270)
			(size 0.6096 1.3208)
			(layers "F.Cu" "F.Mask" "F.Paste")
			(net "THERMAL_ADDR_A1")
		)
		(pad "7" smd rect
			(at 2.649982 -0.635 270)
			(size 0.6096 1.3208)
			(layers "F.Cu" "F.Mask" "F.Paste")
			(net "THERMAL_ADDR_A0")
		)
		(pad "8" smd rect
			(at 2.649982 -1.905 270)
			(size 0.6096 1.3208)
			(layers "F.Cu" "F.Mask" "F.Paste")
			(net "P3V3_STBY")
		)
	)
	(footprint ""
		(layer "F.Cu")
		(at 19.558 -24.13)
		(property "Reference" "R35"
			(at 0.381 -4.16433 0)
			(unlocked yes)
			(layer "F.SilkS")
			(effects
				(font
					(size 0.7874 0.5842)
					(thickness 0.1524)
				)
			)
		)
		(property "Value" ""
			(at 0 0 0)
			(layer "F.Fab")
			(effects
				(font
					(size 1.27 1.27)
				)
			)
		)
		(duplicate_pad_numbers_are_jumpers no)
		(fp_line
			(start -0.7874 -0.4064)
			(end 0.7874 -0.4064)
			(stroke
				(width 0.1524)
				(type default)
			)
			(layer "F.SilkS")
		)
		(fp_line
			(start -0.7874 0.4064)
			(end -0.7874 -0.4064)
			(stroke
				(width 0.1524)
				(type default)
			)
			(layer "F.SilkS")
		)
		(fp_line
			(start 0.7874 -0.4064)
			(end 0.7874 0.4064)
			(stroke
				(width 0.1524)
				(type default)
			)
			(layer "F.SilkS")
		)
		(fp_line
			(start 0.7874 0.4064)
			(end -0.7874 0.4064)
			(stroke
				(width 0.1524)
				(type default)
			)
			(layer "F.SilkS")
		)
		(fp_line
			(start -0.67945 -0.305054)
			(end -0.12065 -0.305054)
			(stroke
				(width 0.1)
				(type default)
			)
			(layer "F.Fab")
		)
		(fp_line
			(start -0.67945 0.3048)
			(end -0.67945 -0.305054)
			(stroke
				(width 0.1)
				(type default)
			)
			(layer "F.Fab")
		)
		(fp_line
			(start -0.12065 -0.305054)
			(end -0.12065 -0.2794)
			(stroke
				(width 0.1)
				(type default)
			)
			(layer "F.Fab")
		)
		(fp_line
			(start -0.12065 -0.2794)
			(end 0.12065 -0.2794)
			(stroke
				(width 0.1)
				(type default)
			)
			(layer "F.Fab")
		)
		(fp_line
			(start -0.12065 0.2794)
			(end -0.12065 0.3048)
			(stroke
				(width 0.1)
				(type default)
			)
			(layer "F.Fab")
		)
		(fp_line
			(start -0.12065 0.3048)
			(end -0.67945 0.3048)
			(stroke
				(width 0.1)
				(type default)
			)
			(layer "F.Fab")
		)
		(fp_line
			(start 0.120396 0.2794)
			(end -0.12065 0.2794)
			(stroke
				(width 0.1)
				(type default)
			)
			(layer "F.Fab")
		)
		(fp_line
			(start 0.120396 0.3048)
			(end 0.120396 0.2794)
			(stroke
				(width 0.1)
				(type default)
			)
			(layer "F.Fab")
		)
		(fp_line
			(start 0.12065 -0.3048)
			(end 0.67945 -0.3048)
			(stroke
				(width 0.1)
				(type default)
			)
			(layer "F.Fab")
		)
		(fp_line
			(start 0.12065 -0.2794)
			(end 0.12065 -0.3048)
			(stroke
				(width 0.1)
				(type default)
			)
			(layer "F.Fab")
		)
		(fp_line
			(start 0.67945 -0.3048)
			(end 0.67945 0.3048)
			(stroke
				(width 0.1)
				(type default)
			)
			(layer "F.Fab")
		)
		(fp_line
			(start 0.67945 0.3048)
			(end 0.120396 0.3048)
			(stroke
				(width 0.1)
				(type default)
			)
			(layer "F.Fab")
		)
		(pad "1" smd circle
			(at -0.40005 0)
			(size 0 0)
			(layers "F.Cu" "F.Mask" "F.Paste")
			(net "SMB_SDA")
		)
		(pad "2" smd circle
			(at 0.40005 0)
			(size 0 0)
			(layers "F.Cu" "F.Mask" "F.Paste")
			(net "SMB_TMP75_SDA")
		)
	)
	(footprint ""
		(layer "F.Cu")
		(at 36.703 -25.4 180)
		(property "Reference" "R40"
			(at 7.874 0.35433 0)
			(unlocked yes)
			(layer "F.SilkS")
			(effects
				(font
					(size 0.7874 0.5842)
					(thickness 0.1524)
				)
			)
		)
		(property "Value" ""
			(at 0 0 180)
			(layer "F.Fab")
			(effects
				(font
					(size 1.27 1.27)
				)
			)
		)
		(duplicate_pad_numbers_are_jumpers no)
		(fp_line
			(start 0.7874 0.4064)
			(end -0.7874 0.4064)
			(stroke
				(width 0.1524)
				(type default)
			)
			(layer "F.SilkS")
		)
		(fp_line
			(start 0.7874 -0.4064)
			(end 0.7874 0.4064)
			(stroke
				(width 0.1524)
				(type default)
			)
			(layer "F.SilkS")
		)
		(fp_line
			(start -0.7874 0.4064)
			(end -0.7874 -0.4064)
			(stroke
				(width 0.1524)
				(type default)
			)
			(layer "F.SilkS")
		)
		(fp_line
			(start -0.7874 -0.4064)
			(end 0.7874 -0.4064)
			(stroke
				(width 0.1524)
				(type default)
			)
			(layer "F.SilkS")
		)
		(fp_line
			(start 0.67945 0.3048)
			(end 0.120396 0.3048)
			(stroke
				(width 0.1)
				(type default)
			)
			(layer "F.Fab")
		)
		(fp_line
			(start 0.67945 -0.3048)
			(end 0.67945 0.3048)
			(stroke
				(width 0.1)
				(type default)
			)
			(layer "F.Fab")
		)
		(fp_line
			(start 0.12065 -0.2794)
			(end 0.12065 -0.3048)
			(stroke
				(width 0.1)
				(type default)
			)
			(layer "F.Fab")
		)
		(fp_line
			(start 0.12065 -0.3048)
			(end 0.67945 -0.3048)
			(stroke
				(width 0.1)
				(type default)
			)
			(layer "F.Fab")
		)
		(fp_line
			(start 0.120396 0.3048)
			(end 0.120396 0.2794)
			(stroke
				(width 0.1)
				(type default)
			)
			(layer "F.Fab")
		)
		(fp_line
			(start 0.120396 0.2794)
			(end -0.12065 0.2794)
			(stroke
				(width 0.1)
				(type default)
			)
			(layer "F.Fab")
		)
		(fp_line
			(start -0.12065 0.3048)
			(end -0.67945 0.3048)
			(stroke
				(width 0.1)
				(type default)
			)
			(layer "F.Fab")
		)
		(fp_line
			(start -0.12065 0.2794)
			(end -0.12065 0.3048)
			(stroke
				(width 0.1)
				(type default)
			)
			(layer "F.Fab")
		)
		(fp_line
			(start -0.12065 -0.2794)
			(end 0.12065 -0.2794)
			(stroke
				(width 0.1)
				(type default)
			)
			(layer "F.Fab")
		)
		(fp_line
			(start -0.12065 -0.305054)
			(end -0.12065 -0.2794)
			(stroke
				(width 0.1)
				(type default)
			)
			(layer "F.Fab")
		)
		(fp_line
			(start -0.67945 0.3048)
			(end -0.67945 -0.305054)
			(stroke
				(width 0.1)
				(type default)
			)
			(layer "F.Fab")
		)
		(fp_line
			(start -0.67945 -0.305054)
			(end -0.12065 -0.305054)
			(stroke
				(width 0.1)
				(type default)
			)
			(layer "F.Fab")
		)
		(pad "1" smd circle
			(at -0.40005 0 180)
			(size 0 0)
			(layers "F.Cu" "F.Mask" "F.Paste")
			(net "P3V3_STBY")
		)
		(pad "2" smd circle
			(at 0.40005 0 180)
			(size 0 0)
			(layers "F.Cu" "F.Mask" "F.Paste")
			(net "NCO380_EN")
		)
	)
	(footprint ""
		(layer "F.Cu")
		(at 15.113 -25.146 -90)
		(property "Reference" "R45"
			(at -2.159 -0.02667 90)
			(unlocked yes)
			(layer "F.SilkS")
			(effects
				(font
					(size 0.7874 0.5842)
					(thickness 0.1524)
				)
			)
		)
		(property "Value" ""
			(at 0 0 270)
			(layer "F.Fab")
			(effects
				(font
					(size 1.27 1.27)
				)
			)
		)
		(duplicate_pad_numbers_are_jumpers no)
		(fp_line
			(start -0.7874 0.4064)
			(end -0.7874 -0.4064)
			(stroke
				(width 0.1524)
				(type default)
			)
			(layer "F.SilkS")
		)
		(fp_line
			(start 0.7874 0.4064)
			(end -0.7874 0.4064)
			(stroke
				(width 0.1524)
				(type default)
			)
			(layer "F.SilkS")
		)
		(fp_line
			(start -0.7874 -0.4064)
			(end 0.7874 -0.4064)
			(stroke
				(width 0.1524)
				(type default)
			)
			(layer "F.SilkS")
		)
		(fp_line
			(start 0.7874 -0.4064)
			(end 0.7874 0.4064)
			(stroke
				(width 0.1524)
				(type default)
			)
			(layer "F.SilkS")
		)
		(fp_line
			(start -0.67945 0.3048)
			(end -0.67945 -0.305054)
			(stroke
				(width 0.1)
				(type default)
			)
			(layer "F.Fab")
		)
		(fp_line
			(start -0.12065 0.3048)
			(end -0.67945 0.3048)
			(stroke
				(width 0.1)
				(type default)
			)
			(layer "F.Fab")
		)
		(fp_line
			(start 0.120396 0.3048)
			(end 0.120396 0.2794)
			(stroke
				(width 0.1)
				(type default)
			)
			(layer "F.Fab")
		)
		(fp_line
			(start 0.67945 0.3048)
			(end 0.120396 0.3048)
			(stroke
				(width 0.1)
				(type default)
			)
			(layer "F.Fab")
		)
		(fp_line
			(start -0.12065 0.2794)
			(end -0.12065 0.3048)
			(stroke
				(width 0.1)
				(type default)
			)
			(layer "F.Fab")
		)
		(fp_line
			(start 0.120396 0.2794)
			(end -0.12065 0.2794)
			(stroke
				(width 0.1)
				(type default)
			)
			(layer "F.Fab")
		)
		(fp_line
			(start -0.12065 -0.2794)
			(end 0.12065 -0.2794)
			(stroke
				(width 0.1)
				(type default)
			)
			(layer "F.Fab")
		)
		(fp_line
			(start 0.12065 -0.2794)
			(end 0.12065 -0.3048)
			(stroke
				(width 0.1)
				(type default)
			)
			(layer "F.Fab")
		)
		(fp_line
			(start 0.12065 -0.3048)
			(end 0.67945 -0.3048)
			(stroke
				(width 0.1)
				(type default)
			)
			(layer "F.Fab")
		)
		(fp_line
			(start 0.67945 -0.3048)
			(end 0.67945 0.3048)
			(stroke
				(width 0.1)
				(type default)
			)
			(layer "F.Fab")
		)
		(fp_line
			(start -0.67945 -0.305054)
			(end -0.12065 -0.305054)
			(stroke
				(width 0.1)
				(type default)
			)
			(layer "F.Fab")
		)
		(fp_line
			(start -0.12065 -0.305054)
			(end -0.12065 -0.2794)
			(stroke
				(width 0.1)
				(type default)
			)
			(layer "F.Fab")
		)
		(pad "1" smd circle
			(at -0.40005 0 270)
			(size 0 0)
			(layers "F.Cu" "F.Mask" "F.Paste")
			(net "P3V3_STBY")
		)
		(pad "2" smd circle
			(at 0.40005 0 270)
			(size 0 0)
			(layers "F.Cu" "F.Mask" "F.Paste")
			(net "PRSNT_DBV2_SLIMSAS")
		)
	)
)
